FILE_TYPE = MACRO_DRAWING;
SET COLOR_WIRE YELLOW;
SET COLOR_PROP MONO;
SET COLOR_DOT WHITE;
SET COLOR_ARC YELLOW;
SET COLOR_BODY GREEN;
SET COLOR_NOTE MONO;
SET PROP_DISPLAY VALUE;
SET PAGE_NUMBER P70;
FORCEADD SKX_EXT_B..17
(-2925 2575);
FORCEPROP 2 LASTPIN (-2225 2225) $PN CL24
J 0
(-2215 2235);
DISPLAY 0.617021 (-2215 2235);
PAINT ORANGE (-2215 2235);
FORCEPROP 2 LASTPIN (-2225 2275) $PN CK77
J 0
(-2215 2285);
DISPLAY 0.617021 (-2215 2285);
PAINT ORANGE (-2215 2285);
FORCEPROP 2 LASTPIN (-2225 2325) $PN CK25
J 0
(-2215 2335);
DISPLAY 0.617021 (-2215 2335);
PAINT ORANGE (-2215 2335);
FORCEPROP 2 LASTPIN (-2225 2375) $PN CK23
J 0
(-2215 2385);
DISPLAY 0.617021 (-2215 2385);
PAINT ORANGE (-2215 2385);
FORCEPROP 2 LASTPIN (-2225 2425) $PN CK19
J 0
(-2215 2435);
DISPLAY 0.617021 (-2215 2435);
PAINT ORANGE (-2215 2435);
FORCEPROP 2 LASTPIN (-2225 2475) $PN CJ26
J 0
(-2215 2485);
DISPLAY 0.617021 (-2215 2485);
PAINT ORANGE (-2215 2485);
FORCEPROP 2 LASTPIN (-2225 2525) $PN CJ24
J 0
(-2215 2535);
DISPLAY 0.617021 (-2215 2535);
PAINT ORANGE (-2215 2535);
FORCEPROP 2 LASTPIN (-2225 2575) $PN CJ22
J 0
(-2215 2585);
DISPLAY 0.617021 (-2215 2585);
PAINT ORANGE (-2215 2585);
FORCEPROP 2 LASTPIN (-2225 2625) $PN CJ20
J 0
(-2215 2635);
DISPLAY 0.617021 (-2215 2635);
PAINT ORANGE (-2215 2635);
FORCEPROP 2 LASTPIN (-2225 2725) $PN CH77
J 0
(-2215 2735);
DISPLAY 0.617021 (-2215 2735);
PAINT ORANGE (-2215 2735);
FORCEPROP 2 LASTPIN (-2225 2775) $PN CH25
J 0
(-2215 2785);
DISPLAY 0.617021 (-2215 2785);
PAINT ORANGE (-2215 2785);
FORCEPROP 2 LASTPIN (-2225 3075) $PN AR16
J 0
(-2215 3085);
DISPLAY 0.617021 (-2215 3085);
PAINT ORANGE (-2215 3085);
FORCEPROP 2 LASTPIN (-2225 3025) $PN AU18
J 0
(-2215 3035);
DISPLAY 0.617021 (-2215 3035);
PAINT ORANGE (-2215 3035);
FORCEPROP 2 LASTPIN (-2225 2975) $PN AW16
J 0
(-2215 2985);
DISPLAY 0.617021 (-2215 2985);
PAINT ORANGE (-2215 2985);
FORCEPROP 2 LASTPIN (-2225 2925) $PN AW20
J 0
(-2215 2935);
DISPLAY 0.617021 (-2215 2935);
PAINT ORANGE (-2215 2935);
FORCEPROP 2 LASTPIN (-2225 2875) $PN AW22
J 0
(-2215 2885);
DISPLAY 0.617021 (-2215 2885);
PAINT ORANGE (-2215 2885);
FORCEPROP 1 LAST MATERIAL IC
J 0
(-3575 3275);
DISPLAY 0.617021 (-3575 3275);
PAINT SKYBLUE (-3575 3275);
FORCEPROP 1 LAST LOCATION U2D1
J 0
(-3575 3325);
DISPLAY 0.617021 (-3575 3325);
PAINT AQUA (-3575 3325);
FORCEPROP 1 LAST PART_NUMBER TBD
J 0
(-3575 2025);
DISPLAY 0.617021 (-3575 2025);
PAINT BLUE (-3575 2025);
FORCEPROP 1 LAST PATH I10
J 0
(-2925 3275);
PAINT GREEN (-2925 3275);
DISPLAY INVISIBLE (-2925 3275);
FORCEPROP 2 LAST CDS_LOCATION U2D1
J 0
(-3575 3325);
DISPLAY 0.617021 (-3575 3325);
PAINT AQUA (-3575 3325);
DISPLAY INVISIBLE (-3575 3325);
FORCEPROP 2 LAST SEC 17
J 0
(-3575 3375);
DISPLAY 0.680851 (-3575 3375);
PAINT MONO (-3575 3375);
DISPLAY INVISIBLE (-3575 3375);
FORCEPROP 2 LAST CDS_LIB chpset_lib
J 0
(-2925 2575);
PAINT ORANGE (-2925 2575);
DISPLAY INVISIBLE (-2925 2575);
FORCEPROP 2 LAST SEC_TYPE BGA1
J 0
(-3575 3375);
DISPLAY 1.021277 (-3575 3375);
PAINT ORANGE (-3575 3375);
DISPLAY INVISIBLE (-3575 3375);
FORCEPROP 1 LAST PACK_TYPE BGA1
J 0
(-3575 3375);
PAINT SKYBLUE (-3575 3375);
DISPLAY INVISIBLE (-3575 3375);
FORCEADD OFFPAGE..1
(-7150 3350);
FORCEPROP 2 LAST $XR0 103 
J 0
(-7402 3350);
DISPLAY 0.638298 (-7402 3350);
PAINT MONO (-7402 3350);
FORCEPROP 2 LAST PATH I11
J 0
(-7400 3400);
DISPLAY 1.021277 (-7400 3400);
PAINT ORANGE (-7400 3400);
DISPLAY INVISIBLE (-7400 3400);
FORCEPROP 1 LAST COMMENT_BODY TRUE
J 0
(-7025 3250);
DISPLAY 0.872340 (-7025 3250);
PAINT GREEN (-7025 3250);
DISPLAY INVISIBLE (-7025 3250);
FORCEPROP 1 LAST OFFPAGE TRUE
J 0
(-6825 3225);
DISPLAY 0.872340 (-6825 3225);
PAINT GREEN (-6825 3225);
DISPLAY INVISIBLE (-6825 3225);
FORCEPROP 2 LAST CDS_LIB mstr_standard
J 0
(-7150 3350);
PAINT MONO (-7150 3350);
DISPLAY INVISIBLE (-7150 3350);
FORCEADD VCC_CORE..1
(-1225 2825);
FORCEPROP 3 LASTPIN (-1225 2775) SIG_NAME PVCCMCP_CPU1\g
J 0
(-1215 2785);
DISPLAY 0.659574 (-1215 2785);
PAINT MONO (-1215 2785);
DISPLAY INVISIBLE (-1215 2785);
FORCEPROP 1 LAST HDL_POWER PVCCMCP_CPU1
J 1
(-1225 2875);
DISPLAY 0.617021 (-1225 2875);
PAINT GREEN (-1225 2875);
FORCEPROP 1 LAST PATH I12
J 0
(-1175 2850);
DISPLAY 0.872340 (-1175 2850);
PAINT AQUA (-1175 2850);
DISPLAY INVISIBLE (-1175 2850);
FORCEPROP 2 LAST CDS_LIB mstr_symbols
J 0
(-1225 2825);
PAINT ORANGE (-1225 2825);
DISPLAY INVISIBLE (-1225 2825);
FORCEADD VCC_CORE..1
(-4000 3775);
FORCEPROP 3 LASTPIN (-4000 3725) SIG_NAME PVCCMCP_CPU1\g
J 0
(-3990 3735);
DISPLAY 0.659574 (-3990 3735);
PAINT MONO (-3990 3735);
DISPLAY INVISIBLE (-3990 3735);
FORCEPROP 1 LAST HDL_POWER PVCCMCP_CPU1
J 1
(-4000 3825);
DISPLAY 0.617021 (-4000 3825);
PAINT GREEN (-4000 3825);
FORCEPROP 1 LAST PATH I13
J 0
(-3950 3800);
DISPLAY 0.872340 (-3950 3800);
PAINT AQUA (-3950 3800);
DISPLAY INVISIBLE (-3950 3800);
FORCEPROP 2 LAST CDS_LIB mstr_symbols
J 0
(-4000 3775);
PAINT ORANGE (-4000 3775);
DISPLAY INVISIBLE (-4000 3775);
FORCEADD VCC_CORE..1
(-7500 2350);
FORCEPROP 3 LASTPIN (-7500 2300) SIG_NAME PVCCMCP_CPU1\g
J 0
(-7490 2310);
DISPLAY 0.659574 (-7490 2310);
PAINT MONO (-7490 2310);
DISPLAY INVISIBLE (-7490 2310);
FORCEPROP 1 LAST HDL_POWER PVCCMCP_CPU1
J 1
(-7500 2400);
DISPLAY 0.617021 (-7500 2400);
PAINT GREEN (-7500 2400);
FORCEPROP 2 LAST CDS_LIB mstr_symbols
J 0
(-7500 2350);
PAINT ORANGE (-7500 2350);
DISPLAY INVISIBLE (-7500 2350);
FORCEPROP 1 LAST PATH I15
J 0
(-7450 2375);
DISPLAY 0.872340 (-7450 2375);
PAINT AQUA (-7450 2375);
DISPLAY INVISIBLE (-7450 2375);
FORCEADD VCC_CORE..1
(-7500 2100);
FORCEPROP 3 LASTPIN (-7500 2050) SIG_NAME PVCCIOMCP_CPU1\g
J 0
(-7490 2060);
DISPLAY 0.659574 (-7490 2060);
PAINT MONO (-7490 2060);
DISPLAY INVISIBLE (-7490 2060);
FORCEPROP 1 LAST HDL_POWER PVCCIOMCP_CPU1
J 1
(-7500 2150);
DISPLAY 0.617021 (-7500 2150);
PAINT GREEN (-7500 2150);
FORCEPROP 0 LAST VOLTAGE +0.95V
J 0
(-7500 2250);
DISPLAY 1.021277 (-7500 2250);
PAINT SKYBLUE (-7500 2250);
DISPLAY INVISIBLE (-7500 2250);
FORCEPROP 1 LAST PATH I16
J 0
(-7450 2125);
DISPLAY 0.872340 (-7450 2125);
PAINT AQUA (-7450 2125);
DISPLAY INVISIBLE (-7450 2125);
FORCEPROP 2 LAST CDS_LIB mstr_symbols
J 0
(-7500 2100);
PAINT MONO (-7500 2100);
DISPLAY INVISIBLE (-7500 2100);
FORCEADD OFFPAGE..1
(-7150 2750);
FORCEPROP 2 LAST $XR0 103 
J 0
(-7402 2750);
DISPLAY 0.638298 (-7402 2750);
PAINT MONO (-7402 2750);
FORCEPROP 2 LAST CDS_LIB mstr_standard
J 0
(-7150 2750);
PAINT MONO (-7150 2750);
DISPLAY INVISIBLE (-7150 2750);
FORCEPROP 1 LAST OFFPAGE TRUE
J 0
(-6825 2625);
DISPLAY 0.872340 (-6825 2625);
PAINT GREEN (-6825 2625);
DISPLAY INVISIBLE (-6825 2625);
FORCEPROP 1 LAST COMMENT_BODY TRUE
J 0
(-7025 2650);
DISPLAY 0.872340 (-7025 2650);
PAINT GREEN (-7025 2650);
DISPLAY INVISIBLE (-7025 2650);
FORCEPROP 2 LAST PATH I7
J 0
(-7425 2800);
DISPLAY 1.021277 (-7425 2800);
PAINT ORANGE (-7425 2800);
DISPLAY INVISIBLE (-7425 2800);
FORCEADD SKX_EXT_B..16
(-5450 2550);
FORCEPROP 1 LAST LOCATION U2D1
J 0
(-6000 3900);
DISPLAY 0.617021 (-6000 3900);
PAINT AQUA (-6000 3900);
FORCEPROP 1 LAST PART_NUMBER TBD
J 0
(-6000 1250);
DISPLAY 0.617021 (-6000 1250);
PAINT BLUE (-6000 1250);
FORCEPROP 1 LAST MATERIAL IC
J 0
(-6000 3850);
DISPLAY 0.617021 (-6000 3850);
PAINT SKYBLUE (-6000 3850);
FORCEPROP 2 LASTPIN (-4850 1900) $PN AY83
J 0
(-4840 1910);
DISPLAY 0.617021 (-4840 1910);
PAINT ORANGE (-4840 1910);
FORCEPROP 2 LASTPIN (-6050 3650) $PN BA78
J 2
(-6060 3660);
DISPLAY 0.617021 (-6060 3660);
PAINT ORANGE (-6060 3660);
FORCEPROP 2 LASTPIN (-6050 3600) $PN BA82
J 2
(-6060 3610);
DISPLAY 0.617021 (-6060 3610);
PAINT ORANGE (-6060 3610);
FORCEPROP 2 LASTPIN (-6050 3550) $PN BB13
J 2
(-6060 3560);
DISPLAY 0.617021 (-6060 3560);
PAINT ORANGE (-6060 3560);
FORCEPROP 2 LASTPIN (-6050 3450) $PN BB17
J 2
(-6060 3460);
DISPLAY 0.617021 (-6060 3460);
PAINT ORANGE (-6060 3460);
FORCEPROP 2 LASTPIN (-6050 3400) $PN BB21
J 2
(-6060 3410);
DISPLAY 0.617021 (-6060 3410);
PAINT ORANGE (-6060 3410);
FORCEPROP 2 LASTPIN (-6050 3350) $PN BB25
J 2
(-6060 3360);
DISPLAY 0.617021 (-6060 3360);
PAINT ORANGE (-6060 3360);
FORCEPROP 2 LASTPIN (-6050 3300) $PN BB65
J 2
(-6060 3310);
DISPLAY 0.617021 (-6060 3310);
PAINT ORANGE (-6060 3310);
FORCEPROP 2 LASTPIN (-6050 3250) $PN BB67
J 2
(-6060 3260);
DISPLAY 0.617021 (-6060 3260);
PAINT ORANGE (-6060 3260);
FORCEPROP 2 LASTPIN (-6050 3200) $PN BC14
J 2
(-6060 3210);
DISPLAY 0.617021 (-6060 3210);
PAINT ORANGE (-6060 3210);
FORCEPROP 2 LASTPIN (-6050 3150) $PN BC18
J 2
(-6060 3160);
DISPLAY 0.617021 (-6060 3160);
PAINT ORANGE (-6060 3160);
FORCEPROP 2 LASTPIN (-6050 3100) $PN BC20
J 2
(-6060 3110);
DISPLAY 0.617021 (-6060 3110);
PAINT ORANGE (-6060 3110);
FORCEPROP 2 LASTPIN (-6050 3050) $PN BC22
J 2
(-6060 3060);
DISPLAY 0.617021 (-6060 3060);
PAINT ORANGE (-6060 3060);
FORCEPROP 2 LASTPIN (-6050 3000) $PN BC64
J 2
(-6060 3010);
DISPLAY 0.617021 (-6060 3010);
PAINT ORANGE (-6060 3010);
FORCEPROP 2 LASTPIN (-6050 2950) $PN BC66
J 2
(-6060 2960);
DISPLAY 0.617021 (-6060 2960);
PAINT ORANGE (-6060 2960);
FORCEPROP 2 LASTPIN (-6050 2900) $PN BC68
J 2
(-6060 2910);
DISPLAY 0.617021 (-6060 2910);
PAINT ORANGE (-6060 2910);
FORCEPROP 2 LASTPIN (-6050 2850) $PN BD17
J 2
(-6060 2860);
DISPLAY 0.617021 (-6060 2860);
PAINT ORANGE (-6060 2860);
FORCEPROP 2 LASTPIN (-6050 2800) $PN BD19
J 2
(-6060 2810);
DISPLAY 0.617021 (-6060 2810);
PAINT ORANGE (-6060 2810);
FORCEPROP 2 LASTPIN (-6050 2650) $PN BD67
J 2
(-6060 2660);
DISPLAY 0.617021 (-6060 2660);
PAINT ORANGE (-6060 2660);
FORCEPROP 2 LASTPIN (-6050 1650) $PN BR22
J 2
(-6060 1660);
DISPLAY 0.617021 (-6060 1660);
PAINT ORANGE (-6060 1660);
FORCEPROP 2 LASTPIN (-6050 1450) $PN BU22
J 2
(-6060 1460);
DISPLAY 0.617021 (-6060 1460);
PAINT ORANGE (-6060 1460);
FORCEPROP 2 LASTPIN (-4850 3650) $PN BV19
J 0
(-4840 3660);
DISPLAY 0.617021 (-4840 3660);
PAINT ORANGE (-4840 3660);
FORCEPROP 2 LASTPIN (-4850 3600) $PN BV21
J 0
(-4840 3610);
DISPLAY 0.617021 (-4840 3610);
PAINT ORANGE (-4840 3610);
FORCEPROP 2 LASTPIN (-4850 3550) $PN BV23
J 0
(-4840 3560);
DISPLAY 0.617021 (-4840 3560);
PAINT ORANGE (-4840 3560);
FORCEPROP 2 LASTPIN (-4850 3500) $PN BW10
J 0
(-4840 3510);
DISPLAY 0.617021 (-4840 3510);
PAINT ORANGE (-4840 3510);
FORCEPROP 2 LASTPIN (-4850 3450) $PN BW20
J 0
(-4840 3460);
DISPLAY 0.617021 (-4840 3460);
PAINT ORANGE (-4840 3460);
FORCEPROP 2 LASTPIN (-4850 3400) $PN BW22
J 0
(-4840 3410);
DISPLAY 0.617021 (-4840 3410);
PAINT ORANGE (-4840 3410);
FORCEPROP 2 LASTPIN (-4850 3350) $PN BY19
J 0
(-4840 3360);
DISPLAY 0.617021 (-4840 3360);
PAINT ORANGE (-4840 3360);
FORCEPROP 2 LASTPIN (-4850 3300) $PN BY25
J 0
(-4840 3310);
DISPLAY 0.617021 (-4840 3310);
PAINT ORANGE (-4840 3310);
FORCEPROP 2 LASTPIN (-4850 3250) $PN CA22
J 0
(-4840 3260);
DISPLAY 0.617021 (-4840 3260);
PAINT ORANGE (-4840 3260);
FORCEPROP 2 LASTPIN (-4850 3200) $PN CA24
J 0
(-4840 3210);
DISPLAY 0.617021 (-4840 3210);
PAINT ORANGE (-4840 3210);
FORCEPROP 2 LASTPIN (-4850 3150) $PN CB19
J 0
(-4840 3160);
DISPLAY 0.617021 (-4840 3160);
PAINT ORANGE (-4840 3160);
FORCEPROP 2 LASTPIN (-4850 3100) $PN CB21
J 0
(-4840 3110);
DISPLAY 0.617021 (-4840 3110);
PAINT ORANGE (-4840 3110);
FORCEPROP 2 LASTPIN (-4850 3050) $PN CB25
J 0
(-4840 3060);
DISPLAY 0.617021 (-4840 3060);
PAINT ORANGE (-4840 3060);
FORCEPROP 2 LASTPIN (-4850 3000) $PN CB5
J 0
(-4840 3010);
DISPLAY 0.617021 (-4840 3010);
PAINT ORANGE (-4840 3010);
FORCEPROP 2 LASTPIN (-4850 2950) $PN CC20
J 0
(-4840 2960);
DISPLAY 0.617021 (-4840 2960);
PAINT ORANGE (-4840 2960);
FORCEPROP 2 LASTPIN (-4850 2900) $PN CC6
J 0
(-4840 2910);
DISPLAY 0.617021 (-4840 2910);
PAINT ORANGE (-4840 2910);
FORCEPROP 2 LASTPIN (-4850 2850) $PN CD19
J 0
(-4840 2860);
DISPLAY 0.617021 (-4840 2860);
PAINT ORANGE (-4840 2860);
FORCEPROP 2 LASTPIN (-4850 2800) $PN CD21
J 0
(-4840 2810);
DISPLAY 0.617021 (-4840 2810);
PAINT ORANGE (-4840 2810);
FORCEPROP 2 LASTPIN (-4850 2750) $PN CD25
J 0
(-4840 2760);
DISPLAY 0.617021 (-4840 2760);
PAINT ORANGE (-4840 2760);
FORCEPROP 2 LASTPIN (-4850 2700) $PN CE22
J 0
(-4840 2710);
DISPLAY 0.617021 (-4840 2710);
PAINT ORANGE (-4840 2710);
FORCEPROP 2 LASTPIN (-4850 2650) $PN CE78
J 0
(-4840 2660);
DISPLAY 0.617021 (-4840 2660);
PAINT ORANGE (-4840 2660);
FORCEPROP 2 LASTPIN (-4850 2600) $PN CE80
J 0
(-4840 2610);
DISPLAY 0.617021 (-4840 2610);
PAINT ORANGE (-4840 2610);
FORCEPROP 2 LASTPIN (-4850 2550) $PN CF19
J 0
(-4840 2560);
DISPLAY 0.617021 (-4840 2560);
PAINT ORANGE (-4840 2560);
FORCEPROP 2 LASTPIN (-4850 2500) $PN CF21
J 0
(-4840 2510);
DISPLAY 0.617021 (-4840 2510);
PAINT ORANGE (-4840 2510);
FORCEPROP 2 LASTPIN (-4850 2450) $PN CF23
J 0
(-4840 2460);
DISPLAY 0.617021 (-4840 2460);
PAINT ORANGE (-4840 2460);
FORCEPROP 2 LASTPIN (-4850 2400) $PN CF79
J 0
(-4840 2410);
DISPLAY 0.617021 (-4840 2410);
PAINT ORANGE (-4840 2410);
FORCEPROP 2 LASTPIN (-4850 2350) $PN CF81
J 0
(-4840 2360);
DISPLAY 0.617021 (-4840 2360);
PAINT ORANGE (-4840 2360);
FORCEPROP 2 LASTPIN (-4850 2300) $PN CG10
J 0
(-4840 2310);
DISPLAY 0.617021 (-4840 2310);
PAINT ORANGE (-4840 2310);
FORCEPROP 2 LASTPIN (-4850 2250) $PN CG20
J 0
(-4840 2260);
DISPLAY 0.617021 (-4840 2260);
PAINT ORANGE (-4840 2260);
FORCEPROP 2 LASTPIN (-4850 2200) $PN CG24
J 0
(-4840 2210);
DISPLAY 0.617021 (-4840 2210);
PAINT ORANGE (-4840 2210);
FORCEPROP 2 LASTPIN (-4850 2150) $PN CG26
J 0
(-4840 2160);
DISPLAY 0.617021 (-4840 2160);
PAINT ORANGE (-4840 2160);
FORCEPROP 2 LASTPIN (-4850 2100) $PN CG78
J 0
(-4840 2110);
DISPLAY 0.617021 (-4840 2110);
PAINT ORANGE (-4840 2110);
FORCEPROP 2 LASTPIN (-4850 2050) $PN CG82
J 0
(-4840 2060);
DISPLAY 0.617021 (-4840 2060);
PAINT ORANGE (-4840 2060);
FORCEPROP 2 LASTPIN (-4850 2000) $PN CH21
J 0
(-4840 2010);
DISPLAY 0.617021 (-4840 2010);
PAINT ORANGE (-4840 2010);
FORCEPROP 2 LASTPIN (-4850 1950) $PN CH23
J 0
(-4840 1960);
DISPLAY 0.617021 (-4840 1960);
PAINT ORANGE (-4840 1960);
FORCEPROP 2 LASTPIN (-6050 2700) $PN BD65
J 2
(-6060 2710);
DISPLAY 0.617021 (-6060 2710);
PAINT ORANGE (-6060 2710);
FORCEPROP 2 LASTPIN (-6050 1600) $PN BR24
J 2
(-6060 1610);
DISPLAY 0.617021 (-6060 1610);
PAINT ORANGE (-6060 1610);
FORCEPROP 2 LASTPIN (-6050 2750) $PN BD25
J 2
(-6060 2760);
DISPLAY 0.617021 (-6060 2760);
PAINT ORANGE (-6060 2760);
FORCEPROP 2 LASTPIN (-6050 2300) $PN BG20
J 2
(-6060 2310);
DISPLAY 0.617021 (-6060 2310);
PAINT ORANGE (-6060 2310);
FORCEPROP 2 LASTPIN (-6050 2350) $PN BG18
J 2
(-6060 2360);
DISPLAY 0.617021 (-6060 2360);
PAINT ORANGE (-6060 2360);
FORCEPROP 2 LASTPIN (-6050 2400) $PN BF21
J 2
(-6060 2410);
DISPLAY 0.617021 (-6060 2410);
PAINT ORANGE (-6060 2410);
FORCEPROP 2 LASTPIN (-6050 2450) $PN BE22
J 2
(-6060 2460);
DISPLAY 0.617021 (-6060 2460);
PAINT ORANGE (-6060 2460);
FORCEPROP 2 LASTPIN (-6050 2500) $PN BE20
J 2
(-6060 2510);
DISPLAY 0.617021 (-6060 2510);
PAINT ORANGE (-6060 2510);
FORCEPROP 2 LASTPIN (-6050 2550) $PN BE18
J 2
(-6060 2560);
DISPLAY 0.617021 (-6060 2560);
PAINT ORANGE (-6060 2560);
FORCEPROP 2 LASTPIN (-6050 2600) $PN BD69
J 2
(-6060 2610);
DISPLAY 0.617021 (-6060 2610);
PAINT ORANGE (-6060 2610);
FORCEPROP 2 LASTPIN (-6050 2200) $PN BJ16
J 2
(-6060 2210);
DISPLAY 0.617021 (-6060 2210);
PAINT ORANGE (-6060 2210);
FORCEPROP 2 LASTPIN (-6050 2250) $PN BH19
J 2
(-6060 2260);
DISPLAY 0.617021 (-6060 2260);
PAINT ORANGE (-6060 2260);
FORCEPROP 2 LASTPIN (-6050 2050) $PN BK17
J 2
(-6060 2060);
DISPLAY 0.617021 (-6060 2060);
PAINT ORANGE (-6060 2060);
FORCEPROP 2 LASTPIN (-6050 2000) $PN BL18
J 2
(-6060 2010);
DISPLAY 0.617021 (-6060 2010);
PAINT ORANGE (-6060 2010);
FORCEPROP 2 LASTPIN (-6050 1950) $PN BL20
J 2
(-6060 1960);
DISPLAY 0.617021 (-6060 1960);
PAINT ORANGE (-6060 1960);
FORCEPROP 2 LASTPIN (-6050 1850) $PN BM19
J 2
(-6060 1860);
DISPLAY 0.617021 (-6060 1860);
PAINT ORANGE (-6060 1860);
FORCEPROP 2 LASTPIN (-6050 1900) $PN BM17
J 2
(-6060 1910);
DISPLAY 0.617021 (-6060 1910);
PAINT ORANGE (-6060 1910);
FORCEPROP 2 LASTPIN (-6050 1800) $PN BN18
J 2
(-6060 1810);
DISPLAY 0.617021 (-6060 1810);
PAINT ORANGE (-6060 1810);
FORCEPROP 2 LASTPIN (-6050 1750) $PN BP17
J 2
(-6060 1760);
DISPLAY 0.617021 (-6060 1760);
PAINT ORANGE (-6060 1760);
FORCEPROP 2 LASTPIN (-6050 1700) $PN BP21
J 2
(-6060 1710);
DISPLAY 0.617021 (-6060 1710);
PAINT ORANGE (-6060 1710);
FORCEPROP 2 LASTPIN (-6050 1550) $PN BU18
J 2
(-6060 1560);
DISPLAY 0.617021 (-6060 1560);
PAINT ORANGE (-6060 1560);
FORCEPROP 2 LASTPIN (-6050 2150) $PN BJ18
J 2
(-6060 2160);
DISPLAY 0.617021 (-6060 2160);
PAINT ORANGE (-6060 2160);
FORCEPROP 2 LASTPIN (-6050 2100) $PN BJ20
J 2
(-6060 2110);
DISPLAY 0.617021 (-6060 2110);
PAINT ORANGE (-6060 2110);
FORCEPROP 2 LASTPIN (-6050 1500) $PN BU20
J 2
(-6060 1510);
DISPLAY 0.617021 (-6060 1510);
PAINT ORANGE (-6060 1510);
FORCEPROP 2 LASTPIN (-6050 3500) $PN BB15
J 2
(-6060 3510);
DISPLAY 0.617021 (-6060 3510);
PAINT ORANGE (-6060 3510);
FORCEPROP 1 LAST PACK_TYPE BGA1
J 0
(-6000 3950);
PAINT SKYBLUE (-6000 3950);
DISPLAY INVISIBLE (-6000 3950);
FORCEPROP 2 LAST SEC_TYPE BGA1
J 0
(-6000 3950);
DISPLAY 1.021277 (-6000 3950);
PAINT ORANGE (-6000 3950);
DISPLAY INVISIBLE (-6000 3950);
FORCEPROP 2 LAST CDS_LIB chpset_lib
J 0
(-5450 2550);
PAINT ORANGE (-5450 2550);
DISPLAY INVISIBLE (-5450 2550);
FORCEPROP 2 LAST SEC 16
J 0
(-6000 3950);
DISPLAY 0.680851 (-6000 3950);
PAINT MONO (-6000 3950);
DISPLAY INVISIBLE (-6000 3950);
FORCEPROP 2 LAST CDS_LOCATION U2D1
J 0
(-6000 3900);
DISPLAY 0.617021 (-6000 3900);
PAINT AQUA (-6000 3900);
DISPLAY INVISIBLE (-6000 3900);
FORCEPROP 1 LAST PATH I9
J 0
(-5450 3850);
PAINT GREEN (-5450 3850);
DISPLAY INVISIBLE (-5450 3850);
FORCEADD DESIGN_NOTE..1
(-4225 1600);
FORCEPROP 0 LAST L1 CPU SYMBOLS 1-30 ARE PRELIMINARY AND SUBJECT TO CHANGE
J 0
(-4425 1475);
DISPLAY 1.021277 (-4425 1475);
PAINT ORANGE (-4425 1475);
FORCEPROP 1 LAST COMMENT_BODY TRUE
J 0
(-4200 1700);
DISPLAY 0.978723 (-4200 1700);
PAINT ORANGE (-4200 1700);
DISPLAY INVISIBLE (-4200 1700);
FORCEPROP 2 LAST CDS_LIB mstr_symbols
J 0
(-4225 1600);
PAINT ORANGE (-4225 1600);
DISPLAY INVISIBLE (-4225 1600);
FORCEADD PRELIM..10
(-5465 2665);
PAINT GRAY (-5465 2665);
FORCEPROP 1 LAST COMMENT_BODY TRUE
J 0
(-5465 2665);
PAINT ORANGE (-5465 2665);
DISPLAY INVISIBLE (-5465 2665);
FORCEPROP 2 LAST CDS_LIB mstr_misc
J 0
(-5465 2665);
PAINT ORANGE (-5465 2665);
DISPLAY INVISIBLE (-5465 2665);
FORCEADD PRELIM..10
(-3090 2715);
PAINT GRAY (-3090 2715);
FORCEPROP 1 LAST COMMENT_BODY TRUE
J 0
(-3090 2715);
PAINT ORANGE (-3090 2715);
DISPLAY INVISIBLE (-3090 2715);
FORCEPROP 2 LAST CDS_LIB mstr_misc
J 0
(-3090 2715);
PAINT ORANGE (-3090 2715);
DISPLAY INVISIBLE (-3090 2715);
FORCEADD INTEL_CORP_BPAGE..1
(0 0);
FORCEPROP 1 LAST CDS_CON_LAST_MODIFIED Fri Jun 16 17:48:26 2017
J 0
(-1425 325);
DISPLAY 1.340426 (-1425 325);
PAINT GREEN (-1425 325);
DISPLAY INVISIBLE (-1425 325);
FORCEPROP 1 LAST CUSTOM_TXT_CDS <CURRENT_DESIGN_SHEET> OF <TOTAL_DESIGN_SHEETS>
J 0
(-500 25);
PAINT ORANGE (-500 25);
FORCEPROP 1 LAST CUSTOM_TXT_CDS <CON_LAST_MODIFIED>
J 0
(-4000 100);
PAINT ORANGE (-4000 100);
FORCEPROP 2 LAST CUSTOM_TXT_CDS <XR_PAGE_TITLE>
J 0
(-7890 5250);
DISPLAY 0.638298 (-7890 5250);
PAINT PINK (-7890 5250);
DISPLAY INVISIBLE (-7890 5250);
FORCEPROP 1 LAST SCH_TITLE SKYLAKE - SKT1 - 16 OF 21
J 0
(-7950 50);
DISPLAY 1.212766 (-7950 50);
PAINT GREEN (-7950 50);
FORCEPROP 1 LAST COMMENT_BODY TRUE
J 0
(12 12);
DISPLAY 0.638298 (12 12);
PAINT GREEN (12 12);
DISPLAY INVISIBLE (12 12);
FORCEPROP 2 LAST CDS_LIB mstr_symbols
J 0
(0 0);
PAINT ORANGE (0 0);
DISPLAY INVISIBLE (0 0);
FORCEPROP 2 LAST PAGE_BORDER TRUE
J 0
(-7890 5250);
DISPLAY 0.851064 (-7890 5250);
PAINT PINK (-7890 5250);
DISPLAY INVISIBLE (-7890 5250);
FORCEPROP 2 LAST CDS_XR_PAGE_TITLE CR-70 : @BASEBOARD_FAB2_LIB.BASEBOARD_FAB2(SCH_1):PAGE70
J 0
(-7890 5250);
DISPLAY 0.638298 (-7890 5250);
PAINT PINK (-7890 5250);
DISPLAY INVISIBLE (-7890 5250);
FORCEADD DESIGN_NOTE..1
(-7550 3900);
FORCEPROP 0 LAST L1 MCP CLK IS USED FOR DEBUG ONLY
J 0
(-7725 3775);
DISPLAY 1.021277 (-7725 3775);
PAINT ORANGE (-7725 3775);
FORCEPROP 1 LAST COMMENT_BODY TRUE
J 0
(-7525 4000);
DISPLAY 0.978723 (-7525 4000);
PAINT ORANGE (-7525 4000);
DISPLAY INVISIBLE (-7525 4000);
FORCEPROP 2 LAST CDS_LIB mstr_symbols
J 0
(-7550 3900);
PAINT ORANGE (-7550 3900);
DISPLAY INVISIBLE (-7550 3900);
WIRE 16 -1 (-1225 2625)(-1225 2775);
WIRE 16 -1 (-2050 2625)(-1225 2625);
WIRE 16 -1 (-1225 2375)(-1225 2625);
WIRE 16 -1 (-1225 2225)(-1225 2375);
WIRE 16 -1 (-2050 2375)(-1225 2375);
WIRE 16 -1 (-2050 2575)(-2050 2625);
WIRE 16 -1 (-2225 2625)(-2050 2625);
WIRE 16 -1 (-2050 2525)(-2050 2575);
WIRE 16 -1 (-2225 2575)(-2050 2575);
WIRE 16 -1 (-2050 2325)(-2050 2375);
WIRE 16 -1 (-2225 2375)(-2050 2375);
WIRE 16 -1 (-2225 2225)(-1225 2225);
WIRE 16 -1 (-2225 2325)(-2050 2325);
WIRE 16 -1 (-2050 2475)(-2050 2525);
WIRE 16 -1 (-2225 2525)(-2050 2525);
WIRE 16 -1 (-2225 2475)(-2050 2475);
WIRE 16 -1 (-4000 3650)(-4000 3725);
WIRE 16 -1 (-4000 3600)(-4000 3650);
WIRE 16 -1 (-4850 3650)(-4000 3650);
WIRE 16 -1 (-4000 3450)(-4000 3600);
WIRE 16 -1 (-4850 3600)(-4000 3600);
WIRE 16 -1 (-4000 3350)(-4000 3450);
WIRE 16 -1 (-4850 3450)(-4000 3450);
WIRE 16 -1 (-4000 3250)(-4000 3350);
WIRE 16 -1 (-4850 3350)(-4000 3350);
WIRE 16 -1 (-4000 3150)(-4000 3250);
WIRE 16 -1 (-4850 3250)(-4000 3250);
WIRE 16 -1 (-4000 3100)(-4000 3150);
WIRE 16 -1 (-4850 3150)(-4000 3150);
WIRE 16 -1 (-4000 2950)(-4000 3100);
WIRE 16 -1 (-4850 3100)(-4000 3100);
WIRE 16 -1 (-4000 2850)(-4000 2950);
WIRE 16 -1 (-4850 2950)(-4000 2950);
WIRE 16 -1 (-4000 2800)(-4000 2850);
WIRE 16 -1 (-4850 2850)(-4000 2850);
WIRE 16 -1 (-4000 2700)(-4000 2800);
WIRE 16 -1 (-4850 2800)(-4000 2800);
WIRE 16 -1 (-4000 2550)(-4000 2700);
WIRE 16 -1 (-4850 2700)(-4000 2700);
WIRE 16 -1 (-4000 2500)(-4000 2550);
WIRE 16 -1 (-4850 2550)(-4000 2550);
WIRE 16 -1 (-4000 2450)(-4000 2500);
WIRE 16 -1 (-4850 2500)(-4000 2500);
WIRE 16 -1 (-4000 2250)(-4000 2450);
WIRE 16 -1 (-4850 2450)(-4000 2450);
WIRE 16 -1 (-4000 2150)(-4000 2250);
WIRE 16 -1 (-4850 2250)(-4000 2250);
WIRE 16 -1 (-4000 2000)(-4000 2150);
WIRE 16 -1 (-4850 2150)(-4000 2150);
WIRE 16 -1 (-4000 1950)(-4000 2000);
WIRE 16 -1 (-4850 2000)(-4000 2000);
WIRE 16 -1 (-4850 1950)(-4000 1950);
WIRE 16 -1 (-7500 2250)(-7500 2300);
WIRE 16 -1 (-7100 2250)(-7500 2250);
WIRE 16 -1 (-7100 2200)(-7100 2250);
WIRE 16 -1 (-6050 2250)(-7100 2250);
WIRE 16 -1 (-7100 2150)(-7100 2200);
WIRE 16 -1 (-6050 2200)(-7100 2200);
WIRE 16 -1 (-7100 2100)(-7100 2150);
WIRE 16 -1 (-6050 2150)(-7100 2150);
WIRE 16 -1 (-7100 2050)(-7100 2100);
WIRE 16 -1 (-6050 2100)(-7100 2100);
WIRE 16 -1 (-7100 2050)(-7100 1950);
WIRE 16 -1 (-6050 2050)(-7100 2050);
WIRE 16 -1 (-7100 1850)(-7100 1950);
WIRE 16 -1 (-6050 1950)(-7100 1950);
WIRE 16 -1 (-7100 1700)(-7100 1850);
WIRE 16 -1 (-6050 1850)(-7100 1850);
WIRE 16 -1 (-7100 1650)(-7100 1700);
WIRE 16 -1 (-6050 1700)(-7100 1700);
WIRE 16 -1 (-7100 1600)(-7100 1650);
WIRE 16 -1 (-6050 1650)(-7100 1650);
WIRE 16 -1 (-7100 1500)(-7100 1600);
WIRE 16 -1 (-6050 1600)(-7100 1600);
WIRE 16 -1 (-7100 1450)(-7100 1500);
WIRE 16 -1 (-6050 1500)(-7100 1500);
WIRE 16 -1 (-6050 1450)(-7100 1450);
WIRE 16 -1 (-7500 2050)(-7500 2000);
WIRE 16 -1 (-7500 1900)(-7500 2000);
WIRE 16 -1 (-6050 2000)(-7500 2000);
WIRE 16 -1 (-7500 1800)(-7500 1900);
WIRE 16 -1 (-6050 1900)(-7500 1900);
WIRE 16 -1 (-7500 1750)(-7500 1800);
WIRE 16 -1 (-6050 1800)(-7500 1800);
WIRE 16 -1 (-7500 1550)(-7500 1750);
WIRE 16 -1 (-6050 1750)(-7500 1750);
WIRE 16 -1 (-6050 1550)(-7500 1550);
WIRE 16 -1 (-7100 3500)(-6050 3500);
FORCEPROP 2 LAST SIG_NAME TP_CPU1_RSVD_168
J 0
(-7042 3509);
DISPLAY 0.617021 (-7042 3509);
PAINT ORANGE (-7042 3509);
FORCEPROP 2 LASTPROP $XRERR UNIQUE?
J 0
(-7340 3500);
DISPLAY 0.638298 (-7340 3500);
PAINT MONO (-7340 3500);
DISPLAY INVISIBLE (-7340 3500);
WIRE 16 -1 (-7100 2550)(-6050 2550);
FORCEPROP 2 LAST SIG_NAME TP_CPU1_RSVD_149
J 0
(-7042 2559);
DISPLAY 0.617021 (-7042 2559);
PAINT ORANGE (-7042 2559);
FORCEPROP 2 LASTPROP $XRERR UNIQUE?
J 0
(-7340 2550);
DISPLAY 0.638298 (-7340 2550);
PAINT MONO (-7340 2550);
DISPLAY INVISIBLE (-7340 2550);
WIRE 16 -1 (-7100 2500)(-6050 2500);
FORCEPROP 2 LAST SIG_NAME TP_CPU1_RSVD_148
J 0
(-7042 2509);
DISPLAY 0.617021 (-7042 2509);
PAINT ORANGE (-7042 2509);
FORCEPROP 2 LASTPROP $XRERR UNIQUE?
J 0
(-7340 2500);
DISPLAY 0.638298 (-7340 2500);
PAINT MONO (-7340 2500);
DISPLAY INVISIBLE (-7340 2500);
WIRE 16 -1 (-7100 2300)(-6050 2300);
FORCEPROP 2 LAST SIG_NAME TP_CPU1_RSVD_144
J 0
(-7042 2309);
DISPLAY 0.617021 (-7042 2309);
PAINT ORANGE (-7042 2309);
FORCEPROP 2 LASTPROP $XRERR UNIQUE?
J 0
(-7340 2300);
DISPLAY 0.638298 (-7340 2300);
PAINT MONO (-7340 2300);
DISPLAY INVISIBLE (-7340 2300);
WIRE 16 -1 (-7100 2350)(-6050 2350);
FORCEPROP 2 LAST SIG_NAME TP_CPU1_RSVD_145
J 0
(-7042 2359);
DISPLAY 0.617021 (-7042 2359);
PAINT ORANGE (-7042 2359);
FORCEPROP 2 LASTPROP $XRERR UNIQUE?
J 0
(-7340 2350);
DISPLAY 0.638298 (-7340 2350);
PAINT MONO (-7340 2350);
DISPLAY INVISIBLE (-7340 2350);
WIRE 16 -1 (-7100 2400)(-6050 2400);
FORCEPROP 2 LAST SIG_NAME TP_CPU1_RSVD_146
J 0
(-7042 2409);
DISPLAY 0.617021 (-7042 2409);
PAINT ORANGE (-7042 2409);
FORCEPROP 2 LASTPROP $XRERR UNIQUE?
J 0
(-7340 2400);
DISPLAY 0.638298 (-7340 2400);
PAINT MONO (-7340 2400);
DISPLAY INVISIBLE (-7340 2400);
WIRE 16 -1 (-7100 2450)(-6050 2450);
FORCEPROP 2 LAST SIG_NAME TP_CPU1_RSVD_147
J 0
(-7042 2459);
DISPLAY 0.617021 (-7042 2459);
PAINT ORANGE (-7042 2459);
FORCEPROP 2 LASTPROP $XRERR UNIQUE?
J 0
(-7340 2450);
DISPLAY 0.638298 (-7340 2450);
PAINT MONO (-7340 2450);
DISPLAY INVISIBLE (-7340 2450);
WIRE 16 -1 (-7100 2600)(-6050 2600);
FORCEPROP 2 LAST SIG_NAME TP_CPU1_RSVD_150
J 0
(-7042 2609);
DISPLAY 0.617021 (-7042 2609);
PAINT ORANGE (-7042 2609);
FORCEPROP 2 LASTPROP $XRERR UNIQUE?
J 0
(-7340 2600);
DISPLAY 0.638298 (-7340 2600);
PAINT MONO (-7340 2600);
DISPLAY INVISIBLE (-7340 2600);
WIRE 16 -1 (-7100 2750)(-6050 2750);
FORCEPROP 2 LAST SIG_NAME CLK_100M_CPU1_RC_REFCLK1_DP
J 0
(-7042 2759);
DISPLAY 0.617021 (-7042 2759);
PAINT ORANGE (-7042 2759);
WIRE 16 -1 (-7100 2700)(-6050 2700);
FORCEPROP 2 LAST SIG_NAME TP_CPU1_RSVD_152
J 0
(-7042 2709);
DISPLAY 0.617021 (-7042 2709);
PAINT ORANGE (-7042 2709);
FORCEPROP 2 LASTPROP $XRERR UNIQUE?
J 0
(-7340 2700);
DISPLAY 0.638298 (-7340 2700);
PAINT MONO (-7340 2700);
DISPLAY INVISIBLE (-7340 2700);
WIRE 16 -1 (-7100 2650)(-6050 2650);
FORCEPROP 2 LAST SIG_NAME TP_CPU1_RSVD_151
J 0
(-7042 2659);
DISPLAY 0.617021 (-7042 2659);
PAINT ORANGE (-7042 2659);
FORCEPROP 2 LASTPROP $XRERR UNIQUE?
J 0
(-7340 2650);
DISPLAY 0.638298 (-7340 2650);
PAINT MONO (-7340 2650);
DISPLAY INVISIBLE (-7340 2650);
WIRE 16 -1 (-7100 2800)(-6050 2800);
FORCEPROP 2 LAST SIG_NAME TP_CPU1_RSVD_154
J 0
(-7042 2809);
DISPLAY 0.617021 (-7042 2809);
PAINT ORANGE (-7042 2809);
FORCEPROP 2 LASTPROP $XRERR UNIQUE?
J 0
(-7340 2800);
DISPLAY 0.638298 (-7340 2800);
PAINT MONO (-7340 2800);
DISPLAY INVISIBLE (-7340 2800);
WIRE 16 -1 (-4175 1900)(-4850 1900);
FORCEPROP 2 LAST SIG_NAME TP_CPU1_RSVD_255
J 0
(-4692 1909);
DISPLAY 0.617021 (-4692 1909);
PAINT ORANGE (-4692 1909);
FORCEPROP 2 LASTPROP $XRERR UNIQUE?
J 0
(-4145 1900);
DISPLAY 0.638298 (-4145 1900);
PAINT MONO (-4145 1900);
DISPLAY INVISIBLE (-4145 1900);
WIRE 16 -1 (-7100 3650)(-6050 3650);
FORCEPROP 2 LAST SIG_NAME TP_CPU1_RSVD_171
J 0
(-7042 3659);
DISPLAY 0.617021 (-7042 3659);
PAINT ORANGE (-7042 3659);
FORCEPROP 2 LASTPROP $XRERR UNIQUE?
J 0
(-7340 3650);
DISPLAY 0.638298 (-7340 3650);
PAINT MONO (-7340 3650);
DISPLAY INVISIBLE (-7340 3650);
WIRE 16 -1 (-7100 3600)(-6050 3600);
FORCEPROP 2 LAST SIG_NAME TP_CPU1_RSVD_170
J 0
(-7042 3609);
DISPLAY 0.617021 (-7042 3609);
PAINT ORANGE (-7042 3609);
FORCEPROP 2 LASTPROP $XRERR UNIQUE?
J 0
(-7340 3600);
DISPLAY 0.638298 (-7340 3600);
PAINT MONO (-7340 3600);
DISPLAY INVISIBLE (-7340 3600);
WIRE 16 -1 (-7100 3550)(-6050 3550);
FORCEPROP 2 LAST SIG_NAME TP_CPU1_RSVD_169
J 0
(-7042 3559);
DISPLAY 0.617021 (-7042 3559);
PAINT ORANGE (-7042 3559);
FORCEPROP 2 LASTPROP $XRERR UNIQUE?
J 0
(-7340 3550);
DISPLAY 0.638298 (-7340 3550);
PAINT MONO (-7340 3550);
DISPLAY INVISIBLE (-7340 3550);
WIRE 16 -1 (-7100 3450)(-6050 3450);
FORCEPROP 2 LAST SIG_NAME TP_CPU1_RSVD_167
J 0
(-7042 3459);
DISPLAY 0.617021 (-7042 3459);
PAINT ORANGE (-7042 3459);
FORCEPROP 2 LASTPROP $XRERR UNIQUE?
J 0
(-7340 3450);
DISPLAY 0.638298 (-7340 3450);
PAINT MONO (-7340 3450);
DISPLAY INVISIBLE (-7340 3450);
WIRE 16 -1 (-7100 3400)(-6050 3400);
FORCEPROP 2 LAST SIG_NAME TP_CPU1_RSVD_166
J 0
(-7042 3409);
DISPLAY 0.617021 (-7042 3409);
PAINT ORANGE (-7042 3409);
FORCEPROP 2 LASTPROP $XRERR UNIQUE?
J 0
(-7340 3400);
DISPLAY 0.638298 (-7340 3400);
PAINT MONO (-7340 3400);
DISPLAY INVISIBLE (-7340 3400);
WIRE 16 -1 (-7100 3350)(-6050 3350);
FORCEPROP 2 LAST SIG_NAME CLK_100M_CPU1_RC_REFCLK1_DN
J 0
(-7042 3359);
DISPLAY 0.617021 (-7042 3359);
PAINT ORANGE (-7042 3359);
WIRE 16 -1 (-7100 3300)(-6050 3300);
FORCEPROP 2 LAST SIG_NAME TP_CPU1_RSVD_164
J 0
(-7042 3309);
DISPLAY 0.617021 (-7042 3309);
PAINT ORANGE (-7042 3309);
FORCEPROP 2 LASTPROP $XRERR UNIQUE?
J 0
(-7340 3300);
DISPLAY 0.638298 (-7340 3300);
PAINT MONO (-7340 3300);
DISPLAY INVISIBLE (-7340 3300);
WIRE 16 -1 (-7100 3250)(-6050 3250);
FORCEPROP 2 LAST SIG_NAME TP_CPU1_RSVD_163
J 0
(-7042 3259);
DISPLAY 0.617021 (-7042 3259);
PAINT ORANGE (-7042 3259);
FORCEPROP 2 LASTPROP $XRERR UNIQUE?
J 0
(-7340 3250);
DISPLAY 0.638298 (-7340 3250);
PAINT MONO (-7340 3250);
DISPLAY INVISIBLE (-7340 3250);
WIRE 16 -1 (-7100 3200)(-6050 3200);
FORCEPROP 2 LAST SIG_NAME TP_CPU1_RSVD_162
J 0
(-7042 3209);
DISPLAY 0.617021 (-7042 3209);
PAINT ORANGE (-7042 3209);
FORCEPROP 2 LASTPROP $XRERR UNIQUE?
J 0
(-7340 3200);
DISPLAY 0.638298 (-7340 3200);
PAINT MONO (-7340 3200);
DISPLAY INVISIBLE (-7340 3200);
WIRE 16 -1 (-7100 3150)(-6050 3150);
FORCEPROP 2 LAST SIG_NAME TP_CPU1_RSVD_161
J 0
(-7042 3159);
DISPLAY 0.617021 (-7042 3159);
PAINT ORANGE (-7042 3159);
FORCEPROP 2 LASTPROP $XRERR UNIQUE?
J 0
(-7340 3150);
DISPLAY 0.638298 (-7340 3150);
PAINT MONO (-7340 3150);
DISPLAY INVISIBLE (-7340 3150);
WIRE 16 -1 (-7100 3100)(-6050 3100);
FORCEPROP 2 LAST SIG_NAME TP_CPU1_RSVD_160
J 0
(-7042 3109);
DISPLAY 0.617021 (-7042 3109);
PAINT ORANGE (-7042 3109);
FORCEPROP 2 LASTPROP $XRERR UNIQUE?
J 0
(-7340 3100);
DISPLAY 0.638298 (-7340 3100);
PAINT MONO (-7340 3100);
DISPLAY INVISIBLE (-7340 3100);
WIRE 16 -1 (-7100 3050)(-6050 3050);
FORCEPROP 2 LAST SIG_NAME TP_CPU1_RSVD_159
J 0
(-7042 3059);
DISPLAY 0.617021 (-7042 3059);
PAINT ORANGE (-7042 3059);
FORCEPROP 2 LASTPROP $XRERR UNIQUE?
J 0
(-7340 3050);
DISPLAY 0.638298 (-7340 3050);
PAINT MONO (-7340 3050);
DISPLAY INVISIBLE (-7340 3050);
WIRE 16 -1 (-7100 3000)(-6050 3000);
FORCEPROP 2 LAST SIG_NAME TP_CPU1_RSVD_158
J 0
(-7042 3009);
DISPLAY 0.617021 (-7042 3009);
PAINT ORANGE (-7042 3009);
FORCEPROP 2 LASTPROP $XRERR UNIQUE?
J 0
(-7340 3000);
DISPLAY 0.638298 (-7340 3000);
PAINT MONO (-7340 3000);
DISPLAY INVISIBLE (-7340 3000);
WIRE 16 -1 (-7100 2950)(-6050 2950);
FORCEPROP 2 LAST SIG_NAME TP_CPU1_RSVD_157
J 0
(-7042 2959);
DISPLAY 0.617021 (-7042 2959);
PAINT ORANGE (-7042 2959);
FORCEPROP 2 LASTPROP $XRERR UNIQUE?
J 0
(-7340 2950);
DISPLAY 0.638298 (-7340 2950);
PAINT MONO (-7340 2950);
DISPLAY INVISIBLE (-7340 2950);
WIRE 16 -1 (-7100 2900)(-6050 2900);
FORCEPROP 2 LAST SIG_NAME TP_CPU1_RSVD_156
J 0
(-7042 2909);
DISPLAY 0.617021 (-7042 2909);
PAINT ORANGE (-7042 2909);
FORCEPROP 2 LASTPROP $XRERR UNIQUE?
J 0
(-7340 2900);
DISPLAY 0.638298 (-7340 2900);
PAINT MONO (-7340 2900);
DISPLAY INVISIBLE (-7340 2900);
WIRE 16 -1 (-7100 2850)(-6050 2850);
FORCEPROP 2 LAST SIG_NAME TP_CPU1_RSVD_155
J 0
(-7042 2859);
DISPLAY 0.617021 (-7042 2859);
PAINT ORANGE (-7042 2859);
FORCEPROP 2 LASTPROP $XRERR UNIQUE?
J 0
(-7340 2850);
DISPLAY 0.638298 (-7340 2850);
PAINT MONO (-7340 2850);
DISPLAY INVISIBLE (-7340 2850);
WIRE 16 -1 (-4175 3550)(-4850 3550);
FORCEPROP 2 LAST SIG_NAME TP_CPU1_RSVD_124
J 0
(-4692 3559);
DISPLAY 0.617021 (-4692 3559);
PAINT ORANGE (-4692 3559);
FORCEPROP 2 LASTPROP $XRERR UNIQUE?
J 0
(-4145 3550);
DISPLAY 0.638298 (-4145 3550);
PAINT MONO (-4145 3550);
DISPLAY INVISIBLE (-4145 3550);
WIRE 16 -1 (-4175 3500)(-4850 3500);
FORCEPROP 2 LAST SIG_NAME TP_CPU1_RSVD_123
J 0
(-4692 3509);
DISPLAY 0.617021 (-4692 3509);
PAINT ORANGE (-4692 3509);
FORCEPROP 2 LASTPROP $XRERR UNIQUE?
J 0
(-4145 3500);
DISPLAY 0.638298 (-4145 3500);
PAINT MONO (-4145 3500);
DISPLAY INVISIBLE (-4145 3500);
WIRE 16 -1 (-4175 3400)(-4850 3400);
FORCEPROP 2 LAST SIG_NAME TP_CPU1_RSVD_121
J 0
(-4692 3409);
DISPLAY 0.617021 (-4692 3409);
PAINT ORANGE (-4692 3409);
FORCEPROP 2 LASTPROP $XRERR UNIQUE?
J 0
(-4145 3400);
DISPLAY 0.638298 (-4145 3400);
PAINT MONO (-4145 3400);
DISPLAY INVISIBLE (-4145 3400);
WIRE 16 -1 (-4175 3300)(-4850 3300);
FORCEPROP 2 LAST SIG_NAME TP_CPU1_RSVD_119
J 0
(-4692 3309);
DISPLAY 0.617021 (-4692 3309);
PAINT ORANGE (-4692 3309);
FORCEPROP 2 LASTPROP $XRERR UNIQUE?
J 0
(-4145 3300);
DISPLAY 0.638298 (-4145 3300);
PAINT MONO (-4145 3300);
DISPLAY INVISIBLE (-4145 3300);
WIRE 16 -1 (-4175 3200)(-4850 3200);
FORCEPROP 2 LAST SIG_NAME TP_CPU1_RSVD_117
J 0
(-4692 3209);
DISPLAY 0.617021 (-4692 3209);
PAINT ORANGE (-4692 3209);
FORCEPROP 2 LASTPROP $XRERR UNIQUE?
J 0
(-4145 3200);
DISPLAY 0.638298 (-4145 3200);
PAINT MONO (-4145 3200);
DISPLAY INVISIBLE (-4145 3200);
WIRE 16 -1 (-4175 3050)(-4850 3050);
FORCEPROP 2 LAST SIG_NAME TP_CPU1_RSVD_114
J 0
(-4692 3059);
DISPLAY 0.617021 (-4692 3059);
PAINT ORANGE (-4692 3059);
FORCEPROP 2 LASTPROP $XRERR UNIQUE?
J 0
(-4145 3050);
DISPLAY 0.638298 (-4145 3050);
PAINT MONO (-4145 3050);
DISPLAY INVISIBLE (-4145 3050);
WIRE 16 -1 (-4175 3000)(-4850 3000);
FORCEPROP 2 LAST SIG_NAME TP_CPU1_RSVD_113
J 0
(-4692 3009);
DISPLAY 0.617021 (-4692 3009);
PAINT ORANGE (-4692 3009);
FORCEPROP 2 LASTPROP $XRERR UNIQUE?
J 0
(-4145 3000);
DISPLAY 0.638298 (-4145 3000);
PAINT MONO (-4145 3000);
DISPLAY INVISIBLE (-4145 3000);
WIRE 16 -1 (-4175 2900)(-4850 2900);
FORCEPROP 2 LAST SIG_NAME TP_CPU1_RSVD_111
J 0
(-4692 2909);
DISPLAY 0.617021 (-4692 2909);
PAINT ORANGE (-4692 2909);
FORCEPROP 2 LASTPROP $XRERR UNIQUE?
J 0
(-4145 2900);
DISPLAY 0.638298 (-4145 2900);
PAINT MONO (-4145 2900);
DISPLAY INVISIBLE (-4145 2900);
WIRE 16 -1 (-4175 2750)(-4850 2750);
FORCEPROP 2 LAST SIG_NAME TP_CPU1_RSVD_108
J 0
(-4692 2759);
DISPLAY 0.617021 (-4692 2759);
PAINT ORANGE (-4692 2759);
FORCEPROP 2 LASTPROP $XRERR UNIQUE?
J 0
(-4145 2750);
DISPLAY 0.638298 (-4145 2750);
PAINT MONO (-4145 2750);
DISPLAY INVISIBLE (-4145 2750);
WIRE 16 -1 (-4175 2650)(-4850 2650);
FORCEPROP 2 LAST SIG_NAME TP_CPU1_RSVD_106
J 0
(-4692 2659);
DISPLAY 0.617021 (-4692 2659);
PAINT ORANGE (-4692 2659);
FORCEPROP 2 LASTPROP $XRERR UNIQUE?
J 0
(-4145 2650);
DISPLAY 0.638298 (-4145 2650);
PAINT MONO (-4145 2650);
DISPLAY INVISIBLE (-4145 2650);
WIRE 16 -1 (-4850 2600)(-4175 2600);
FORCEPROP 2 LAST SIG_NAME TP_CPU1_RSVD_105
J 0
(-4692 2609);
DISPLAY 0.617021 (-4692 2609);
PAINT ORANGE (-4692 2609);
FORCEPROP 2 LASTPROP $XRERR UNIQUE?
J 0
(-4145 2600);
DISPLAY 0.638298 (-4145 2600);
PAINT MONO (-4145 2600);
DISPLAY INVISIBLE (-4145 2600);
WIRE 16 -1 (-4175 2400)(-4850 2400);
FORCEPROP 2 LAST SIG_NAME TP_CPU1_RSVD_101
J 0
(-4692 2409);
DISPLAY 0.617021 (-4692 2409);
PAINT ORANGE (-4692 2409);
FORCEPROP 2 LASTPROP $XRERR UNIQUE?
J 0
(-4145 2400);
DISPLAY 0.638298 (-4145 2400);
PAINT MONO (-4145 2400);
DISPLAY INVISIBLE (-4145 2400);
WIRE 16 -1 (-4175 2350)(-4850 2350);
FORCEPROP 2 LAST SIG_NAME TP_CPU1_RSVD_100
J 0
(-4692 2359);
DISPLAY 0.617021 (-4692 2359);
PAINT ORANGE (-4692 2359);
FORCEPROP 2 LASTPROP $XRERR UNIQUE?
J 0
(-4145 2350);
DISPLAY 0.638298 (-4145 2350);
PAINT MONO (-4145 2350);
DISPLAY INVISIBLE (-4145 2350);
WIRE 16 -1 (-4175 2300)(-4850 2300);
FORCEPROP 2 LAST SIG_NAME TP_CPU1_RSVD_99
J 0
(-4692 2309);
DISPLAY 0.617021 (-4692 2309);
PAINT ORANGE (-4692 2309);
FORCEPROP 2 LASTPROP $XRERR UNIQUE?
J 0
(-4145 2300);
DISPLAY 0.638298 (-4145 2300);
PAINT MONO (-4145 2300);
DISPLAY INVISIBLE (-4145 2300);
WIRE 16 -1 (-4175 2200)(-4850 2200);
FORCEPROP 2 LAST SIG_NAME TP_CPU1_RSVD_97
J 0
(-4692 2209);
DISPLAY 0.617021 (-4692 2209);
PAINT ORANGE (-4692 2209);
FORCEPROP 2 LASTPROP $XRERR UNIQUE?
J 0
(-4145 2200);
DISPLAY 0.638298 (-4145 2200);
PAINT MONO (-4145 2200);
DISPLAY INVISIBLE (-4145 2200);
WIRE 16 -1 (-4175 2100)(-4850 2100);
FORCEPROP 2 LAST SIG_NAME TP_CPU1_RSVD_95
J 0
(-4692 2109);
DISPLAY 0.617021 (-4692 2109);
PAINT ORANGE (-4692 2109);
FORCEPROP 2 LASTPROP $XRERR UNIQUE?
J 0
(-4145 2100);
DISPLAY 0.638298 (-4145 2100);
PAINT MONO (-4145 2100);
DISPLAY INVISIBLE (-4145 2100);
WIRE 16 -1 (-4175 2050)(-4850 2050);
FORCEPROP 2 LAST SIG_NAME TP_CPU1_RSVD_94
J 0
(-4692 2059);
DISPLAY 0.617021 (-4692 2059);
PAINT ORANGE (-4692 2059);
FORCEPROP 2 LASTPROP $XRERR UNIQUE?
J 0
(-4145 2050);
DISPLAY 0.638298 (-4145 2050);
PAINT MONO (-4145 2050);
DISPLAY INVISIBLE (-4145 2050);
WIRE 16 -1 (-1550 2925)(-2225 2925);
FORCEPROP 2 LAST SIG_NAME TP_CPU1_TEST_9
J 0
(-2075 2935);
DISPLAY 0.617021 (-2075 2935);
PAINT ORANGE (-2075 2935);
FORCEPROP 2 LASTPROP $XRERR UNIQUE?
J 0
(-1520 2925);
DISPLAY 0.638298 (-1520 2925);
PAINT MONO (-1520 2925);
DISPLAY INVISIBLE (-1520 2925);
WIRE 16 -1 (-1550 2975)(-2225 2975);
FORCEPROP 2 LAST SIG_NAME TP_CPU1_TEST_8
J 0
(-2075 2985);
DISPLAY 0.617021 (-2075 2985);
PAINT ORANGE (-2075 2985);
FORCEPROP 2 LASTPROP $XRERR UNIQUE?
J 0
(-1520 2975);
DISPLAY 0.638298 (-1520 2975);
PAINT MONO (-1520 2975);
DISPLAY INVISIBLE (-1520 2975);
WIRE 16 -1 (-2225 3025)(-1550 3025);
FORCEPROP 2 LAST SIG_NAME TP_CPU1_TEST_7
J 0
(-2075 3035);
DISPLAY 0.617021 (-2075 3035);
PAINT ORANGE (-2075 3035);
FORCEPROP 2 LASTPROP $XRERR UNIQUE?
J 0
(-1520 3025);
DISPLAY 0.638298 (-1520 3025);
PAINT MONO (-1520 3025);
DISPLAY INVISIBLE (-1520 3025);
WIRE 16 -1 (-1550 3075)(-2225 3075);
FORCEPROP 2 LAST SIG_NAME TP_CPU1_TEST_6
J 0
(-2075 3085);
DISPLAY 0.617021 (-2075 3085);
PAINT ORANGE (-2075 3085);
FORCEPROP 2 LASTPROP $XRERR UNIQUE?
J 0
(-1520 3075);
DISPLAY 0.638298 (-1520 3075);
PAINT MONO (-1520 3075);
DISPLAY INVISIBLE (-1520 3075);
WIRE 16 -1 (-1550 2875)(-2225 2875);
FORCEPROP 2 LAST SIG_NAME TP_CPU1_TEST_10
J 0
(-2075 2885);
DISPLAY 0.617021 (-2075 2885);
PAINT ORANGE (-2075 2885);
FORCEPROP 2 LASTPROP $XRERR UNIQUE?
J 0
(-1520 2875);
DISPLAY 0.638298 (-1520 2875);
PAINT MONO (-1520 2875);
DISPLAY INVISIBLE (-1520 2875);
WIRE 16 -1 (-1550 2275)(-2225 2275);
FORCEPROP 2 LAST SIG_NAME TP_CPU1_RSVD_82
J 0
(-2075 2285);
DISPLAY 0.617021 (-2075 2285);
PAINT ORANGE (-2075 2285);
FORCEPROP 2 LASTPROP $XRERR UNIQUE?
J 0
(-1520 2275);
DISPLAY 0.638298 (-1520 2275);
PAINT MONO (-1520 2275);
DISPLAY INVISIBLE (-1520 2275);
WIRE 16 -1 (-2225 2425)(-1550 2425);
FORCEPROP 2 LAST SIG_NAME TP_CPU1_RSVD_85
J 0
(-2075 2435);
DISPLAY 0.617021 (-2075 2435);
PAINT ORANGE (-2075 2435);
FORCEPROP 2 LASTPROP $XRERR UNIQUE?
J 0
(-1520 2425);
DISPLAY 0.638298 (-1520 2425);
PAINT MONO (-1520 2425);
DISPLAY INVISIBLE (-1520 2425);
WIRE 16 -1 (-1550 2725)(-2225 2725);
FORCEPROP 2 LAST SIG_NAME TP_CPU1_RSVD_90
J 0
(-2075 2735);
DISPLAY 0.617021 (-2075 2735);
PAINT ORANGE (-2075 2735);
FORCEPROP 2 LASTPROP $XRERR UNIQUE?
J 0
(-1520 2725);
DISPLAY 0.638298 (-1520 2725);
PAINT MONO (-1520 2725);
DISPLAY INVISIBLE (-1520 2725);
WIRE 16 -1 (-1550 2775)(-2225 2775);
FORCEPROP 2 LAST SIG_NAME TP_CPU1_RSVD_91
J 0
(-2075 2785);
DISPLAY 0.617021 (-2075 2785);
PAINT ORANGE (-2075 2785);
FORCEPROP 2 LASTPROP $XRERR UNIQUE?
J 0
(-1520 2775);
DISPLAY 0.638298 (-1520 2775);
PAINT MONO (-1520 2775);
DISPLAY INVISIBLE (-1520 2775);
DOT 1 (-7100 1650);
DOT 1 (-7100 2150);
DOT 1 (-7100 1500);
DOT 1 (-7100 2050);
DOT 1 (-7100 2100);
DOT 1 (-7100 2200);
DOT 1 (-7100 2250);
DOT 1 (-4000 2800);
DOT 1 (-4000 3650);
DOT 1 (-4000 3600);
DOT 1 (-4000 3450);
DOT 1 (-4000 3350);
DOT 1 (-4000 3250);
DOT 1 (-4000 3150);
DOT 1 (-4000 3100);
DOT 1 (-4000 2950);
DOT 1 (-4000 2850);
DOT 1 (-4000 2700);
DOT 1 (-4000 2550);
DOT 1 (-4000 2500);
DOT 1 (-4000 2450);
DOT 1 (-4000 2250);
DOT 1 (-4000 2150);
DOT 1 (-4000 2000);
DOT 1 (-1225 2375);
DOT 1 (-1225 2625);
DOT 1 (-2050 2375);
DOT 1 (-2050 2525);
DOT 1 (-2050 2575);
DOT 1 (-2050 2625);
DOT 1 (-7100 1850);
DOT 1 (-7500 2000);
DOT 1 (-7100 1950);
DOT 1 (-7500 1900);
DOT 1 (-7100 1700);
DOT 1 (-7500 1800);
DOT 1 (-7500 1750);
DOT 1 (-7100 1600);
FORCENOTE
BOM_COST=PROC_SOCKET
(-7925 200) 0;
DISPLAY LEFT (-7925 200);
DISPLAY 1.723404 (-7925 200);
PAINT PURPLE (-7925 200);
FORCENOTE
ROOM=CPU1
(-7925 325) 0;
DISPLAY LEFT (-7925 325);
DISPLAY 1.723404 (-7925 325);
PAINT PURPLE (-7925 325);
QUIT
